(kicad_pcb
	(version 20260206)
	(generator "pcbnew")
	(generator_version "10.0")
	(general
		(thickness 1.6)
		(legacy_teardrops no)
	)
	(paper "A4")
	(title_block
		(title "fcb — Lightning_FCB_BRD.brd")
		(comment 1 "Lightning (Wiwynn / Facebook NVMe JBOF) / footprints 174-180 of 495")
	)
	(layers
		(0 "F.Cu" signal "TOP")
		(4 "In1.Cu" signal "L2GND")
		(6 "In2.Cu" signal "L3VCC")
		(2 "B.Cu" signal "BOTTOM")
		(9 "F.Adhes" user "F.Adhesive")
		(11 "B.Adhes" user "B.Adhesive")
		(13 "F.Paste" user "Package Geometry/Pastemask Top")
		(15 "B.Paste" user "Package Geometry/Pastemask Bottom")
		(5 "F.SilkS" user "Ref Des/Silkscreen Top")
		(7 "B.SilkS" user "Ref Des/Silkscreen Bottom")
		(1 "F.Mask" user "Board Geometry/Soldermask Top")
		(3 "B.Mask" user "Board Geometry/Soldermask Bottom")
		(17 "Dwgs.User" user "User.Drawings")
		(19 "Cmts.User" user "User.Comments")
		(21 "Eco1.User" user "User.Eco1")
		(23 "Eco2.User" user "User.Eco2")
		(25 "Edge.Cuts" user "Board Geometry/Outline")
		(27 "Margin" user)
		(31 "F.CrtYd" user "Package Geometry/Place Bound Top")
		(29 "B.CrtYd" user "Package Geometry/Place Bound Bottom")
		(35 "F.Fab" user "Ref Des/Assembly Top")
		(33 "B.Fab" user "Ref Des/Assembly Bottom")
	)
	(footprint ""
		(layer "F.Cu")
		(at 26.4922 -250.444 -90)
		(property "Reference" "C14"
			(at 0 0 270)
			(layer "F.SilkS")
			(hide yes)
			(effects
				(font
					(size 1.27 1.27)
				)
			)
		)
		(property "Value" "SCD1U50V3KX-GP"
			(at 0 -2.8194 270)
			(unlocked yes)
			(layer "F.Fab")
			(hide yes)
			(effects
				(font
					(size 1.016 1.016)
					(thickness 0.1524)
				)
			)
		)
		(property "Device Type" "C603H36"
			(at 0 -4.3434 270)
			(unlocked yes)
			(layer "F.Fab")
			(hide yes)
			(effects
				(font
					(size 1.016 1.016)
					(thickness 0.1524)
				)
			)
		)
		(duplicate_pad_numbers_are_jumpers no)
		(fp_line
			(start 0.508 0)
			(end -0.508 0)
			(stroke
				(width 0.2032)
				(type default)
			)
			(layer "F.SilkS")
		)
		(fp_rect
			(start -0.5842 1.3335)
			(end 0.5842 -1.3335)
			(stroke
				(width 0)
				(type default)
			)
			(fill no)
			(layer "F.CrtYd")
		)
		(fp_rect
			(start -0.5842 1.3335)
			(end 0.5842 -1.3335)
			(stroke
				(width 0)
				(type default)
			)
			(fill no)
			(layer "F.Fab")
		)
		(pad "1" smd custom
			(at 0 -0.762 270)
			(size 0.2159 0.2159)
			(layers "F.Cu" "F.Mask" "F.Paste")
			(net "P3V3")
			(options
				(clearance outline)
				(anchor circle)
			)
			(primitives
				(gr_poly
					(pts
						(arc
							(start -0.3302 -0.4318)
							(mid -0.402042 -0.402042)
							(end -0.4318 -0.3302)
						)
						(arc
							(start -0.4318 0.3302)
							(mid -0.402042 0.402042)
							(end -0.3302 0.4318)
						)
						(arc
							(start 0.3302 0.4318)
							(mid 0.402042 0.402042)
							(end 0.4318 0.3302)
						)
						(arc
							(start 0.4318 -0.3302)
							(mid 0.402042 -0.402042)
							(end 0.3302 -0.4318)
						)
					)
					(width 0)
					(fill yes)
				)
			)
		)
		(pad "2" smd custom
			(at 0 0.762 270)
			(size 0.2159 0.2159)
			(layers "F.Cu" "F.Mask" "F.Paste")
			(net "GND")
			(options
				(clearance outline)
				(anchor circle)
			)
			(primitives
				(gr_poly
					(pts
						(arc
							(start -0.3302 -0.4318)
							(mid -0.402042 -0.402042)
							(end -0.4318 -0.3302)
						)
						(arc
							(start -0.4318 0.3302)
							(mid -0.402042 0.402042)
							(end -0.3302 0.4318)
						)
						(arc
							(start 0.3302 0.4318)
							(mid 0.402042 0.402042)
							(end 0.4318 0.3302)
						)
						(arc
							(start 0.4318 -0.3302)
							(mid 0.402042 -0.402042)
							(end 0.3302 -0.4318)
						)
					)
					(width 0)
					(fill yes)
				)
			)
		)
	)
	(footprint ""
		(layer "F.Cu")
		(at 29.5402 -169.9006 180)
		(property "Reference" "R161"
			(at 0 0 180)
			(layer "F.SilkS")
			(hide yes)
			(effects
				(font
					(size 1.27 1.27)
				)
			)
		)
		(property "Value" "0R2J-2-GP"
			(at 0.064008 -3.993896 180)
			(unlocked yes)
			(layer "F.Fab")
			(hide yes)
			(effects
				(font
					(size 1.016 1.016)
					(thickness 0.1524)
				)
			)
		)
		(property "Device Type" "R402H16"
			(at 0.064008 -5.517896 180)
			(unlocked yes)
			(layer "F.Fab")
			(hide yes)
			(effects
				(font
					(size 1.016 1.016)
					(thickness 0.1524)
				)
			)
		)
		(duplicate_pad_numbers_are_jumpers no)
		(fp_line
			(start 0.508 -0.9398)
			(end -0.508 -0.9398)
			(stroke
				(width 0.1524)
				(type default)
			)
			(layer "F.SilkS")
		)
		(fp_line
			(start -0.508 -0.9398)
			(end -0.508 0.9398)
			(stroke
				(width 0.1524)
				(type default)
			)
			(layer "F.SilkS")
		)
		(fp_rect
			(start -0.508 0.9398)
			(end 0.508 -0.9398)
			(stroke
				(width 0)
				(type default)
			)
			(fill no)
			(layer "F.CrtYd")
		)
		(fp_rect
			(start -0.508 0.9398)
			(end 0.508 -0.9398)
			(stroke
				(width 0)
				(type default)
			)
			(fill no)
			(layer "F.Fab")
		)
		(pad "1" smd custom
			(at 0 -0.4445 180)
			(size 0.1397 0.1397)
			(layers "F.Cu" "F.Mask" "F.Paste")
			(net "NCT7904D_PWM1")
			(options
				(clearance outline)
				(anchor circle)
			)
			(primitives
				(gr_poly
					(pts
						(arc
							(start -0.1778 -0.2794)
							(mid -0.249642 -0.249642)
							(end -0.2794 -0.1778)
						)
						(arc
							(start -0.2794 0.1778)
							(mid -0.249642 0.249642)
							(end -0.1778 0.2794)
						)
						(arc
							(start 0.1778 0.2794)
							(mid 0.249642 0.249642)
							(end 0.2794 0.1778)
						)
						(arc
							(start 0.2794 -0.1778)
							(mid 0.249642 -0.249642)
							(end 0.1778 -0.2794)
						)
					)
					(width 0)
					(fill yes)
				)
			)
		)
		(pad "2" smd custom
			(at 0 0.4445 180)
			(size 0.1397 0.1397)
			(layers "F.Cu" "F.Mask" "F.Paste")
			(net "PWM_BUFFER_IN_FAN1_FAN2")
			(options
				(clearance outline)
				(anchor circle)
			)
			(primitives
				(gr_poly
					(pts
						(arc
							(start -0.1778 -0.2794)
							(mid -0.249642 -0.249642)
							(end -0.2794 -0.1778)
						)
						(arc
							(start -0.2794 0.1778)
							(mid -0.249642 0.249642)
							(end -0.1778 0.2794)
						)
						(arc
							(start 0.1778 0.2794)
							(mid 0.249642 0.249642)
							(end 0.2794 0.1778)
						)
						(arc
							(start 0.2794 -0.1778)
							(mid 0.249642 -0.249642)
							(end 0.1778 -0.2794)
						)
					)
					(width 0)
					(fill yes)
				)
			)
		)
	)
	(footprint ""
		(layer "F.Cu")
		(at 32.385 -361.315 180)
		(property "Reference" "R108"
			(at 0 0 180)
			(layer "F.SilkS")
			(hide yes)
			(effects
				(font
					(size 1.27 1.27)
				)
			)
		)
		(property "Value" "0R2J-2-GP"
			(at 0.064008 -3.993896 180)
			(unlocked yes)
			(layer "F.Fab")
			(hide yes)
			(effects
				(font
					(size 1.016 1.016)
					(thickness 0.1524)
				)
			)
		)
		(property "Device Type" "R402H16"
			(at 0.064008 -5.517896 180)
			(unlocked yes)
			(layer "F.Fab")
			(hide yes)
			(effects
				(font
					(size 1.016 1.016)
					(thickness 0.1524)
				)
			)
		)
		(duplicate_pad_numbers_are_jumpers no)
		(fp_line
			(start 0.508 -0.9398)
			(end -0.508 -0.9398)
			(stroke
				(width 0.1524)
				(type default)
			)
			(layer "F.SilkS")
		)
		(fp_line
			(start -0.508 -0.9398)
			(end -0.508 0.9398)
			(stroke
				(width 0.1524)
				(type default)
			)
			(layer "F.SilkS")
		)
		(fp_rect
			(start -0.508 0.9398)
			(end 0.508 -0.9398)
			(stroke
				(width 0)
				(type default)
			)
			(fill no)
			(layer "F.CrtYd")
		)
		(fp_rect
			(start -0.508 0.9398)
			(end 0.508 -0.9398)
			(stroke
				(width 0)
				(type default)
			)
			(fill no)
			(layer "F.Fab")
		)
		(pad "1" smd custom
			(at 0 -0.4445 180)
			(size 0.1397 0.1397)
			(layers "F.Cu" "F.Mask" "F.Paste")
			(net "I2C_C_SCL")
			(options
				(clearance outline)
				(anchor circle)
			)
			(primitives
				(gr_poly
					(pts
						(arc
							(start -0.1778 -0.2794)
							(mid -0.249642 -0.249642)
							(end -0.2794 -0.1778)
						)
						(arc
							(start -0.2794 0.1778)
							(mid -0.249642 0.249642)
							(end -0.1778 0.2794)
						)
						(arc
							(start 0.1778 0.2794)
							(mid 0.249642 0.249642)
							(end 0.2794 0.1778)
						)
						(arc
							(start 0.2794 -0.1778)
							(mid 0.249642 -0.249642)
							(end 0.1778 -0.2794)
						)
					)
					(width 0)
					(fill yes)
				)
			)
		)
		(pad "2" smd custom
			(at 0 0.4445 180)
			(size 0.1397 0.1397)
			(layers "F.Cu" "F.Mask" "F.Paste")
			(net "I2C_C_SCL_ADM1276")
			(options
				(clearance outline)
				(anchor circle)
			)
			(primitives
				(gr_poly
					(pts
						(arc
							(start -0.1778 -0.2794)
							(mid -0.249642 -0.249642)
							(end -0.2794 -0.1778)
						)
						(arc
							(start -0.2794 0.1778)
							(mid -0.249642 0.249642)
							(end -0.1778 0.2794)
						)
						(arc
							(start 0.1778 0.2794)
							(mid 0.249642 0.249642)
							(end 0.2794 0.1778)
						)
						(arc
							(start 0.2794 -0.1778)
							(mid 0.249642 -0.249642)
							(end 0.1778 -0.2794)
						)
					)
					(width 0)
					(fill yes)
				)
			)
		)
	)
	(footprint ""
		(layer "F.Cu")
		(at 19.6088 -178.8668 180)
		(property "Reference" "R91"
			(at 0 0 180)
			(layer "F.SilkS")
			(hide yes)
			(effects
				(font
					(size 1.27 1.27)
				)
			)
		)
		(property "Value" "10KR2F-2-GP"
			(at 0.064008 -3.993896 180)
			(unlocked yes)
			(layer "F.Fab")
			(hide yes)
			(effects
				(font
					(size 1.016 1.016)
					(thickness 0.1524)
				)
			)
		)
		(property "Device Type" "R402H16"
			(at 0.064008 -5.517896 180)
			(unlocked yes)
			(layer "F.Fab")
			(hide yes)
			(effects
				(font
					(size 1.016 1.016)
					(thickness 0.1524)
				)
			)
		)
		(duplicate_pad_numbers_are_jumpers no)
		(fp_line
			(start 0.508 -0.9398)
			(end -0.508 -0.9398)
			(stroke
				(width 0.1524)
				(type default)
			)
			(layer "F.SilkS")
		)
		(fp_line
			(start -0.508 -0.9398)
			(end -0.508 0.9398)
			(stroke
				(width 0.1524)
				(type default)
			)
			(layer "F.SilkS")
		)
		(fp_rect
			(start -0.508 0.9398)
			(end 0.508 -0.9398)
			(stroke
				(width 0)
				(type default)
			)
			(fill no)
			(layer "F.CrtYd")
		)
		(fp_rect
			(start -0.508 0.9398)
			(end 0.508 -0.9398)
			(stroke
				(width 0)
				(type default)
			)
			(fill no)
			(layer "F.Fab")
		)
		(pad "1" smd custom
			(at 0 -0.4445 180)
			(size 0.1397 0.1397)
			(layers "F.Cu" "F.Mask" "F.Paste")
			(net "FANIN_7")
			(options
				(clearance outline)
				(anchor circle)
			)
			(primitives
				(gr_poly
					(pts
						(arc
							(start -0.1778 -0.2794)
							(mid -0.249642 -0.249642)
							(end -0.2794 -0.1778)
						)
						(arc
							(start -0.2794 0.1778)
							(mid -0.249642 0.249642)
							(end -0.1778 0.2794)
						)
						(arc
							(start 0.1778 0.2794)
							(mid 0.249642 0.249642)
							(end 0.2794 0.1778)
						)
						(arc
							(start 0.2794 -0.1778)
							(mid 0.249642 -0.249642)
							(end 0.1778 -0.2794)
						)
					)
					(width 0)
					(fill yes)
				)
			)
		)
		(pad "2" smd custom
			(at 0 0.4445 180)
			(size 0.1397 0.1397)
			(layers "F.Cu" "F.Mask" "F.Paste")
			(net "GND")
			(options
				(clearance outline)
				(anchor circle)
			)
			(primitives
				(gr_poly
					(pts
						(arc
							(start -0.1778 -0.2794)
							(mid -0.249642 -0.249642)
							(end -0.2794 -0.1778)
						)
						(arc
							(start -0.2794 0.1778)
							(mid -0.249642 0.249642)
							(end -0.1778 0.2794)
						)
						(arc
							(start 0.1778 0.2794)
							(mid 0.249642 0.249642)
							(end 0.2794 0.1778)
						)
						(arc
							(start 0.2794 -0.1778)
							(mid 0.249642 -0.249642)
							(end 0.1778 -0.2794)
						)
					)
					(width 0)
					(fill yes)
				)
			)
		)
	)
	(footprint ""
		(layer "F.Cu")
		(at 43.8658 -382.9558 -90)
		(property "Reference" "D14"
			(at 0 0 270)
			(layer "F.SilkS")
			(hide yes)
			(effects
				(font
					(size 1.27 1.27)
				)
			)
		)
		(property "Value" "MBRS340T3G-GP"
			(at 0 -10.6172 270)
			(unlocked yes)
			(layer "F.Fab")
			(hide yes)
			(effects
				(font
					(size 1.016 1.016)
					(thickness 0.1524)
				)
			)
		)
		(property "Device Type" "D8059AKH101"
			(at 0 -12.1412 270)
			(unlocked yes)
			(layer "F.Fab")
			(hide yes)
			(effects
				(font
					(size 1.016 1.016)
					(thickness 0.1524)
				)
			)
		)
		(duplicate_pad_numbers_are_jumpers no)
		(fp_line
			(start 3.175 5.2832)
			(end -3.175 5.2832)
			(stroke
				(width 0.508)
				(type default)
			)
			(layer "F.SilkS")
		)
		(fp_line
			(start -3.175 5.1054)
			(end -3.175 -5.1054)
			(stroke
				(width 0.1524)
				(type default)
			)
			(layer "F.SilkS")
		)
		(fp_line
			(start 3.175 5.1054)
			(end -3.175 5.1054)
			(stroke
				(width 0.1524)
				(type default)
			)
			(layer "F.SilkS")
		)
		(fp_line
			(start -3.175 -5.1054)
			(end 3.175 -5.1054)
			(stroke
				(width 0.1524)
				(type default)
			)
			(layer "F.SilkS")
		)
		(fp_line
			(start 3.175 -5.1054)
			(end 3.175 5.1054)
			(stroke
				(width 0.1524)
				(type default)
			)
			(layer "F.SilkS")
		)
		(fp_rect
			(start -3.429 5.1816)
			(end 3.429 -5.1816)
			(stroke
				(width 0)
				(type default)
			)
			(fill no)
			(layer "F.CrtYd")
		)
		(fp_poly
			(pts
				(xy -3.429 -5.1816) (xy 3.429 -5.1816) (xy 3.429 5.1816) (xy -3.429 5.1816)
			)
			(stroke
				(width 0)
				(type default)
			)
			(fill no)
			(layer "F.Fab")
		)
		(pad "A" smd rect
			(at 0 -3.77571 270)
			(size 3.2512 2.159)
			(layers "F.Cu" "F.Mask" "F.Paste")
			(net "GND")
		)
		(pad "K" smd rect
			(at 0 3.77571 270)
			(size 3.2512 2.159)
			(layers "F.Cu" "F.Mask" "F.Paste")
			(net "P12V")
		)
	)
	(footprint ""
		(layer "F.Cu")
		(at 43.942 -95.7326 90)
		(property "Reference" "TC5"
			(at 0 0 90)
			(layer "F.SilkS")
			(hide yes)
			(effects
				(font
					(size 1.27 1.27)
				)
			)
		)
		(property "Value" "ST68U16VDM-1-GP"
			(at 0 -9.6012 90)
			(unlocked yes)
			(layer "F.Fab")
			(hide yes)
			(effects
				(font
					(size 1.016 1.016)
					(thickness 0.1524)
				)
			)
		)
		(property "Device Type" "CT7343H79"
			(at 0 -11.1252 90)
			(unlocked yes)
			(layer "F.Fab")
			(hide yes)
			(effects
				(font
					(size 1.016 1.016)
					(thickness 0.1524)
				)
			)
		)
		(duplicate_pad_numbers_are_jumpers no)
		(fp_line
			(start 2.286 -4.8768)
			(end -2.286 -4.8768)
			(stroke
				(width 0.1524)
				(type default)
			)
			(layer "F.SilkS")
		)
		(fp_line
			(start -2.286 -4.8768)
			(end -2.286 -2.032)
			(stroke
				(width 0.1524)
				(type default)
			)
			(layer "F.SilkS")
		)
		(fp_line
			(start 2.1082 -4.699)
			(end -2.1082 -4.699)
			(stroke
				(width 0.508)
				(type default)
			)
			(layer "F.SilkS")
		)
		(fp_line
			(start 2.286 -2.032)
			(end 2.286 -4.8768)
			(stroke
				(width 0.1524)
				(type default)
			)
			(layer "F.SilkS")
		)
		(fp_line
			(start 2.286 2.032)
			(end 2.286 4.8768)
			(stroke
				(width 0.1524)
				(type default)
			)
			(layer "F.SilkS")
		)
		(fp_line
			(start 2.286 4.8768)
			(end -2.286 4.8768)
			(stroke
				(width 0.1524)
				(type default)
			)
			(layer "F.SilkS")
		)
		(fp_line
			(start -2.286 4.8768)
			(end -2.286 2.032)
			(stroke
				(width 0.1524)
				(type default)
			)
			(layer "F.SilkS")
		)
		(fp_rect
			(start -2.1463 3.6449)
			(end 2.1463 -3.6449)
			(stroke
				(width 0)
				(type default)
			)
			(fill no)
			(layer "F.CrtYd")
		)
		(fp_poly
			(pts
				(xy -2.54 4.953) (xy -2.54 4.2926) (xy -3.81 4.2926) (xy -3.81 -4.2926) (xy -2.54 -4.2926) (xy -2.54 -4.953)
				(xy 2.54 -4.953) (xy 2.54 -4.2926) (xy 3.81 -4.2926) (xy 3.81 -1.6256) (xy 2.1463 -1.6256) (xy 2.1463 -3.6449)
				(xy -2.1463 -3.6449) (xy -2.1463 3.6449) (xy 2.1463 3.6449) (xy 2.1463 -1.6129) (xy 3.81 -1.6129)
				(xy 3.81 4.2926) (xy 2.54 4.2926) (xy 2.54 4.953)
			)
			(stroke
				(width 0)
				(type default)
			)
			(fill no)
			(layer "F.CrtYd")
		)
		(fp_rect
			(start 2.54 4.2926)
			(end 3.81 -4.2926)
			(stroke
				(width 0)
				(type default)
			)
			(fill no)
			(layer "F.Fab")
		)
		(fp_rect
			(start -3.81 4.2926)
			(end -2.54 -4.2926)
			(stroke
				(width 0)
				(type default)
			)
			(fill no)
			(layer "F.Fab")
		)
		(fp_rect
			(start -2.54 4.953)
			(end 2.54 -4.953)
			(stroke
				(width 0)
				(type default)
			)
			(fill no)
			(layer "F.Fab")
		)
		(pad "1" smd rect
			(at 0 -3.1496 90)
			(size 2.413 2.286)
			(layers "F.Cu" "F.Mask" "F.Paste")
			(net "P12VL")
		)
		(pad "2" smd rect
			(at 0 3.1496 90)
			(size 2.413 2.286)
			(layers "F.Cu" "F.Mask" "F.Paste")
			(net "GND")
		)
		(zone
			(layer "F.Cu")
			(hatch none 0.5)
			(connect_pads
				(clearance 0)
			)
			(min_thickness 0.25)
			(keepout
				(tracks allowed)
				(vias not_allowed)
				(pads allowed)
				(copperpour not_allowed)
				(footprints allowed)
			)
			(placement
				(enabled no)
				(sheetname "")
			)
			(fill
				(thermal_gap 0.5)
				(thermal_bridge_width 0.5)
				(island_removal_mode 0)
			)
			(polygon
				(pts
					(xy 42.2529 -97.2439) (xy 39.3446 -97.2439) (xy 39.3446 -94.2213) (xy 42.2402 -94.2213) (xy 42.5704 -94.2213)
					(xy 42.5704 -97.2439)
				)
			)
		)
		(zone
			(layer "F.Cu")
			(hatch none 0.5)
			(connect_pads
				(clearance 0)
			)
			(min_thickness 0.25)
			(keepout
				(tracks allowed)
				(vias not_allowed)
				(pads allowed)
				(copperpour not_allowed)
				(footprints allowed)
			)
			(placement
				(enabled no)
				(sheetname "")
			)
			(fill
				(thermal_gap 0.5)
				(thermal_bridge_width 0.5)
				(island_removal_mode 0)
			)
			(polygon
				(pts
					(xy 48.5394 -94.2213) (xy 48.5394 -97.2439) (xy 45.6438 -97.2439) (xy 45.3136 -97.2439) (xy 45.3136 -94.2213)
					(xy 45.6438 -94.2213)
				)
			)
		)
	)
	(footprint ""
		(layer "F.Cu")
		(at 8.0772 -275.2344 90)
		(property "Reference" "R38"
			(at 0 0 90)
			(layer "F.SilkS")
			(hide yes)
			(effects
				(font
					(size 1.27 1.27)
				)
			)
		)
		(property "Value" "0R2J-2-GP"
			(at 0.064008 -3.993896 90)
			(unlocked yes)
			(layer "F.Fab")
			(hide yes)
			(effects
				(font
					(size 1.016 1.016)
					(thickness 0.1524)
				)
			)
		)
		(property "Device Type" "R402H16"
			(at 0.064008 -5.517896 90)
			(unlocked yes)
			(layer "F.Fab")
			(hide yes)
			(effects
				(font
					(size 1.016 1.016)
					(thickness 0.1524)
				)
			)
		)
		(duplicate_pad_numbers_are_jumpers no)
		(fp_line
			(start 0.508 -0.9398)
			(end -0.508 -0.9398)
			(stroke
				(width 0.1524)
				(type default)
			)
			(layer "F.SilkS")
		)
		(fp_line
			(start -0.508 -0.9398)
			(end -0.508 0.9398)
			(stroke
				(width 0.1524)
				(type default)
			)
			(layer "F.SilkS")
		)
		(fp_rect
			(start -0.508 0.9398)
			(end 0.508 -0.9398)
			(stroke
				(width 0)
				(type default)
			)
			(fill no)
			(layer "F.CrtYd")
		)
		(fp_rect
			(start -0.508 0.9398)
			(end 0.508 -0.9398)
			(stroke
				(width 0)
				(type default)
			)
			(fill no)
			(layer "F.Fab")
		)
		(pad "1" smd custom
			(at 0 -0.4445 90)
			(size 0.1397 0.1397)
			(layers "F.Cu" "F.Mask" "F.Paste")
			(net "LED_DR_LED2_K")
			(options
				(clearance outline)
				(anchor circle)
			)
			(primitives
				(gr_poly
					(pts
						(arc
							(start -0.1778 -0.2794)
							(mid -0.249642 -0.249642)
							(end -0.2794 -0.1778)
						)
						(arc
							(start -0.2794 0.1778)
							(mid -0.249642 0.249642)
							(end -0.1778 0.2794)
						)
						(arc
							(start 0.1778 0.2794)
							(mid 0.249642 0.249642)
							(end 0.2794 0.1778)
						)
						(arc
							(start 0.2794 -0.1778)
							(mid 0.249642 -0.249642)
							(end 0.1778 -0.2794)
						)
					)
					(width 0)
					(fill yes)
				)
			)
		)
		(pad "2" smd custom
			(at 0 0.4445 90)
			(size 0.1397 0.1397)
			(layers "F.Cu" "F.Mask" "F.Paste")
			(net "GND")
			(options
				(clearance outline)
				(anchor circle)
			)
			(primitives
				(gr_poly
					(pts
						(arc
							(start -0.1778 -0.2794)
							(mid -0.249642 -0.249642)
							(end -0.2794 -0.1778)
						)
						(arc
							(start -0.2794 0.1778)
							(mid -0.249642 0.249642)
							(end -0.1778 0.2794)
						)
						(arc
							(start 0.1778 0.2794)
							(mid 0.249642 0.249642)
							(end 0.2794 0.1778)
						)
						(arc
							(start 0.2794 -0.1778)
							(mid 0.249642 -0.249642)
							(end 0.1778 -0.2794)
						)
					)
					(width 0)
					(fill yes)
				)
			)
		)
	)
)
